(kicad_pcb
	(version 20260206)
	(generator "pcbnew")
	(generator_version "10.0")
	(general
		(thickness 1.6)
		(legacy_teardrops no)
	)
	(paper "A4")
	(title_block
		(title "03242023_DA0F0TMBIJ0_F0T_Motherboard_J_brd_V01_OCP.brd")
		(comment 1 "Grand Teton / footprint 3039 of 6105 (U2), pads 2584-2694 of 4677")
	)
	(layers
		(0 "F.Cu" signal "TOP")
		(4 "In1.Cu" signal "GND")
		(6 "In2.Cu" signal "IN1")
		(8 "In3.Cu" signal "GND1")
		(10 "In4.Cu" signal "IN2")
		(12 "In5.Cu" signal "GND2")
		(14 "In6.Cu" signal "IN3")
		(16 "In7.Cu" signal "GND3")
		(18 "In8.Cu" signal "VCC")
		(20 "In9.Cu" signal "VCC1")
		(22 "In10.Cu" signal "GND4")
		(24 "In11.Cu" signal "IN4")
		(26 "In12.Cu" signal "GND5")
		(28 "In13.Cu" signal "IN5")
		(30 "In14.Cu" signal "GND6")
		(32 "In15.Cu" signal "IN6")
		(34 "In16.Cu" signal "GND7")
		(2 "B.Cu" signal "BOTTOM")
		(9 "F.Adhes" user "F.Adhesive")
		(11 "B.Adhes" user "B.Adhesive")
		(13 "F.Paste" user "Package Geometry/Pastemask Top")
		(15 "B.Paste" user "Package Geometry/Pastemask Bottom")
		(5 "F.SilkS" user "Ref Des/Silkscreen Top")
		(7 "B.SilkS" user "Ref Des/Silkscreen Bottom")
		(1 "F.Mask" user "Board Geometry/Soldermask Top")
		(3 "B.Mask" user "Board Geometry/Soldermask Bottom")
		(17 "Dwgs.User" user "User.Drawings")
		(19 "Cmts.User" user "User.Comments")
		(21 "Eco1.User" user "User.Eco1")
		(23 "Eco2.User" user "User.Eco2")
		(25 "Edge.Cuts" user "Board Geometry/Outline")
		(27 "Margin" user)
		(31 "F.CrtYd" user "Package Geometry/Place Bound Top")
		(29 "B.CrtYd" user "Package Geometry/Place Bound Bottom")
		(35 "F.Fab" user "Ref Des/Assembly Top")
		(33 "B.Fab" user "Ref Des/Assembly Bottom")
	)
	(footprint ""
		(layer "F.Cu")
		(at 359.870248 -251.76988 90)
		(property "Reference" "U2"
			(at -74.416158 -44.488608 0)
			(unlocked yes)
			(layer "F.SilkS")
			(effects
				(font
					(size 1.6002 1.1938)
					(thickness 0.1524)
				)
				(justify left)
			)
		)
		(property "Value" ""
			(at 0 0 90)
			(layer "F.Fab")
			(effects
				(font
					(size 1.27 1.27)
				)
			)
		)
		(duplicate_pad_numbers_are_jumpers no)
		(pad "DE27" smd circle
			(at -16.263874 12.397486 270)
			(size 0.4318 0.4318)
			(layers "F.Cu" "F.Mask" "F.Paste")
			(net "GND")
		)
		(pad "DE29" smd circle
			(at -14.635988 12.397486 270)
			(size 0.4318 0.4318)
			(layers "F.Cu" "F.Mask" "F.Paste")
			(net "GND")
		)
		(pad "DE31" smd circle
			(at -13.008356 12.397486 270)
			(size 0.4318 0.4318)
			(layers "F.Cu" "F.Mask" "F.Paste")
			(net "GND")
		)
		(pad "DE33" smd circle
			(at -11.380724 12.397486 270)
			(size 0.4318 0.4318)
			(layers "F.Cu" "F.Mask" "F.Paste")
			(net "GND")
		)
		(pad "DE35" smd circle
			(at -9.752838 12.397486 270)
			(size 0.4318 0.4318)
			(layers "F.Cu" "F.Mask" "F.Paste")
			(net "GND")
		)
		(pad "DE37" smd circle
			(at -8.124952 12.397486 270)
			(size 0.4318 0.4318)
			(layers "F.Cu" "F.Mask" "F.Paste")
			(net "GND")
		)
		(pad "DE39" smd circle
			(at -6.49732 12.397486 270)
			(size 0.4318 0.4318)
			(layers "F.Cu" "F.Mask" "F.Paste")
			(net "GND")
		)
		(pad "DE41" smd circle
			(at -4.869434 12.397486 270)
			(size 0.4318 0.4318)
			(layers "F.Cu" "F.Mask" "F.Paste")
			(net "GND")
		)
		(pad "DE43" smd circle
			(at -3.241802 12.397486 270)
			(size 0.4318 0.4318)
			(layers "F.Cu" "F.Mask" "F.Paste")
			(net "GND")
		)
		(pad "DE45" smd circle
			(at -1.613916 12.397486 270)
			(size 0.4318 0.4318)
			(layers "F.Cu" "F.Mask" "F.Paste")
			(net "GND")
		)
		(pad "DE48" smd circle
			(at 2.427732 12.507468 270)
			(size 0.4318 0.4318)
			(layers "F.Cu" "F.Mask" "F.Paste")
			(net "GND")
		)
		(pad "DE50" smd circle
			(at 4.055618 12.507468 270)
			(size 0.4318 0.4318)
			(layers "F.Cu" "F.Mask" "F.Paste")
			(net "GND")
		)
		(pad "DE52" smd circle
			(at 5.68325 12.507468 270)
			(size 0.4318 0.4318)
			(layers "F.Cu" "F.Mask" "F.Paste")
			(net "GND")
		)
		(pad "DE54" smd circle
			(at 7.311136 12.507468 270)
			(size 0.4318 0.4318)
			(layers "F.Cu" "F.Mask" "F.Paste")
			(net "GND")
		)
		(pad "DE56" smd circle
			(at 8.939022 12.507468 270)
			(size 0.4318 0.4318)
			(layers "F.Cu" "F.Mask" "F.Paste")
			(net "GND")
		)
		(pad "DE58" smd circle
			(at 10.566654 12.507468 270)
			(size 0.4318 0.4318)
			(layers "F.Cu" "F.Mask" "F.Paste")
			(net "GND")
		)
		(pad "DE60" smd circle
			(at 12.19454 12.507468 270)
			(size 0.4318 0.4318)
			(layers "F.Cu" "F.Mask" "F.Paste")
			(net "GND")
		)
		(pad "DE62" smd circle
			(at 13.822426 12.507468 270)
			(size 0.4318 0.4318)
			(layers "F.Cu" "F.Mask" "F.Paste")
			(net "GND")
		)
		(pad "DE64" smd circle
			(at 15.450058 12.507468 270)
			(size 0.4318 0.4318)
			(layers "F.Cu" "F.Mask" "F.Paste")
			(net "GND")
		)
		(pad "DE66" smd circle
			(at 17.07769 12.507468 270)
			(size 0.4318 0.4318)
			(layers "F.Cu" "F.Mask" "F.Paste")
			(net "GND")
		)
		(pad "DE68" smd circle
			(at 18.705576 12.507468 270)
			(size 0.4318 0.4318)
			(layers "F.Cu" "F.Mask" "F.Paste")
			(net "GND")
		)
		(pad "DE70" smd circle
			(at 20.333462 12.507468 270)
			(size 0.4318 0.4318)
			(layers "F.Cu" "F.Mask" "F.Paste")
			(net "GND")
		)
		(pad "DE72" smd circle
			(at 21.961094 12.507468 270)
			(size 0.4318 0.4318)
			(layers "F.Cu" "F.Mask" "F.Paste")
			(net "GND")
		)
		(pad "DE74" smd circle
			(at 23.58898 12.507468 270)
			(size 0.4318 0.4318)
			(layers "F.Cu" "F.Mask" "F.Paste")
			(net "GND")
		)
		(pad "DE76" smd circle
			(at 25.216612 12.507468 270)
			(size 0.4318 0.4318)
			(layers "F.Cu" "F.Mask" "F.Paste")
			(net "GND")
		)
		(pad "DE78" smd circle
			(at 26.844498 12.507468 270)
			(size 0.4318 0.4318)
			(layers "F.Cu" "F.Mask" "F.Paste")
			(net "GND")
		)
		(pad "DE80" smd circle
			(at 28.472384 12.507468 270)
			(size 0.4318 0.4318)
			(layers "F.Cu" "F.Mask" "F.Paste")
			(net "GND")
		)
		(pad "DE82" smd circle
			(at 30.100016 12.507468 270)
			(size 0.4318 0.4318)
			(layers "F.Cu" "F.Mask" "F.Paste")
			(net "GND")
		)
		(pad "DE84" smd circle
			(at 31.727902 12.507468 270)
			(size 0.4318 0.4318)
			(layers "F.Cu" "F.Mask" "F.Paste")
			(net "GND")
		)
		(pad "DE86" smd circle
			(at 33.355534 12.507468 270)
			(size 0.4318 0.4318)
			(layers "F.Cu" "F.Mask" "F.Paste")
			(net "P5E_CPU0_PE3_TX_DP<10>")
		)
		(pad "DE88" smd circle
			(at 34.98342 12.507468 270)
			(size 0.4318 0.4318)
			(layers "F.Cu" "F.Mask" "F.Paste")
			(net "GND")
		)
		(pad "DE90" smd circle
			(at 36.611306 12.507468 270)
			(size 0.4318 0.4318)
			(layers "F.Cu" "F.Mask" "F.Paste")
			(net "P5E_CPU0_PE3_RX_DP<11>")
		)
		(pad "DF2" smd circle
			(at -36.611306 12.867132 270)
			(size 0.4318 0.4318)
			(layers "F.Cu" "F.Mask" "F.Paste")
			(net "UPI_CPU1_CPU0_P0P1_DP<11>")
		)
		(pad "DF4" smd circle
			(at -34.98342 12.867132 270)
			(size 0.4318 0.4318)
			(layers "F.Cu" "F.Mask" "F.Paste")
			(net "GND")
		)
		(pad "DF6" smd circle
			(at -33.355534 12.867132 270)
			(size 0.4318 0.4318)
			(layers "F.Cu" "F.Mask" "F.Paste")
			(net "UPI_CPU0_CPU1_P1P0_DN<10>")
		)
		(pad "DF8" smd circle
			(at -31.727902 12.867132 270)
			(size 0.4318 0.4318)
			(layers "F.Cu" "F.Mask" "F.Paste")
			(net "GND")
		)
		(pad "DF10" smd circle
			(at -30.100016 12.867132 270)
			(size 0.4318 0.4318)
			(layers "F.Cu" "F.Mask" "F.Paste")
			(net "P5E_CPU0_PE2_RX_DP<4>")
		)
		(pad "DF12" smd circle
			(at -28.472384 12.867132 270)
			(size 0.4318 0.4318)
			(layers "F.Cu" "F.Mask" "F.Paste")
			(net "GND")
		)
		(pad "DF14" smd circle
			(at -26.844498 12.867132 270)
			(size 0.4318 0.4318)
			(layers "F.Cu" "F.Mask" "F.Paste")
			(net "P5E_CPU0_PE2_TX_DN<5>")
		)
		(pad "DF16" smd circle
			(at -25.216612 12.867132 270)
			(size 0.4318 0.4318)
			(layers "F.Cu" "F.Mask" "F.Paste")
			(net "GND")
		)
		(pad "DF18" smd circle
			(at -23.58898 12.867132 270)
			(size 0.4318 0.4318)
			(layers "F.Cu" "F.Mask" "F.Paste")
			(net "M_H_CPU0_SB_DQS_DN<8>")
		)
		(pad "DF20" smd circle
			(at -21.961094 12.867132 270)
			(size 0.4318 0.4318)
			(layers "F.Cu" "F.Mask" "F.Paste")
			(net "M_H_CPU0_SB_DQ<26>")
		)
		(pad "DF22" smd circle
			(at -20.333462 12.867132 270)
			(size 0.4318 0.4318)
			(layers "F.Cu" "F.Mask" "F.Paste")
			(net "M_H_CPU0_SB_DQ<15>")
		)
		(pad "DF24" smd circle
			(at -18.705576 12.867132 270)
			(size 0.4318 0.4318)
			(layers "F.Cu" "F.Mask" "F.Paste")
			(net "M_H_CPU0_SB_DQS_DP<6>")
		)
		(pad "DF26" smd circle
			(at -17.07769 12.867132 270)
			(size 0.4318 0.4318)
			(layers "F.Cu" "F.Mask" "F.Paste")
			(net "M_H_CPU0_SB_DQ<10>")
		)
		(pad "DF28" smd circle
			(at -15.450058 12.867132 270)
			(size 0.4318 0.4318)
			(layers "F.Cu" "F.Mask" "F.Paste")
			(net "M_H_CPU0_SB_DQ<5>")
		)
		(pad "DF30" smd circle
			(at -13.822426 12.867132 270)
			(size 0.4318 0.4318)
			(layers "F.Cu" "F.Mask" "F.Paste")
			(net "M_H_CPU0_SB_DQS_DP<5>")
		)
		(pad "DF32" smd circle
			(at -12.19454 12.867132 270)
			(size 0.4318 0.4318)
			(layers "F.Cu" "F.Mask" "F.Paste")
			(net "M_H_CPU0_SB_DQ<2>")
		)
		(pad "DF34" smd circle
			(at -10.566654 12.867132 270)
			(size 0.4318 0.4318)
			(layers "F.Cu" "F.Mask" "F.Paste")
			(net "M_H_CPU0_SB_CB<3>")
		)
		(pad "DF36" smd circle
			(at -8.939022 12.867132 270)
			(size 0.4318 0.4318)
			(layers "F.Cu" "F.Mask" "F.Paste")
			(net "M_H_CPU0_SB_DQS_DP<4>")
		)
		(pad "DF38" smd circle
			(at -7.311136 12.867132 270)
			(size 0.4318 0.4318)
			(layers "F.Cu" "F.Mask" "F.Paste")
			(net "M_H_CPU0_SB_CB<4>")
		)
		(pad "DF40" smd circle
			(at -5.68325 12.867132 270)
			(size 0.4318 0.4318)
			(layers "F.Cu" "F.Mask" "F.Paste")
			(net "M_H_CPU0_SB_CA<0>")
		)
		(pad "DF42" smd circle
			(at -4.055618 12.867132 270)
			(size 0.4318 0.4318)
			(layers "F.Cu" "F.Mask" "F.Paste")
			(net "M_H_CPU0_CLK_DP<0>")
		)
		(pad "DF44" smd circle
			(at -2.427732 12.867132 270)
			(size 0.4318 0.4318)
			(layers "F.Cu" "F.Mask" "F.Paste")
			(net "M_E_CPU0_SB_RSP<0>")
		)
		(pad "DF47" smd circle
			(at 1.613916 12.977114 270)
			(size 0.4318 0.4318)
			(layers "F.Cu" "F.Mask" "F.Paste")
			(net "M_H_CPU0_SA_CA<5>")
		)
		(pad "DF49" smd circle
			(at 3.241802 12.977114 270)
			(size 0.4318 0.4318)
			(layers "F.Cu" "F.Mask" "F.Paste")
			(net "GND")
		)
		(pad "DF51" smd circle
			(at 4.869434 12.977114 270)
			(size 0.4318 0.4318)
			(layers "F.Cu" "F.Mask" "F.Paste")
			(net "M_H_CPU0_SA_CS_N<0>")
		)
		(pad "DF53" smd circle
			(at 6.49732 12.977114 270)
			(size 0.4318 0.4318)
			(layers "F.Cu" "F.Mask" "F.Paste")
			(net "M_H_CPU0_SA_CB<7>")
		)
		(pad "DF55" smd circle
			(at 8.124952 12.977114 270)
			(size 0.4318 0.4318)
			(layers "F.Cu" "F.Mask" "F.Paste")
			(net "M_H_CPU0_SA_DQS_DP<9>")
		)
		(pad "DF57" smd circle
			(at 9.752838 12.977114 270)
			(size 0.4318 0.4318)
			(layers "F.Cu" "F.Mask" "F.Paste")
			(net "M_H_CPU0_SA_CB<2>")
		)
		(pad "DF59" smd circle
			(at 11.380724 12.977114 270)
			(size 0.4318 0.4318)
			(layers "F.Cu" "F.Mask" "F.Paste")
			(net "M_H_CPU0_SA_DQ<31>")
		)
		(pad "DF61" smd circle
			(at 13.008356 12.977114 270)
			(size 0.4318 0.4318)
			(layers "F.Cu" "F.Mask" "F.Paste")
			(net "M_H_CPU0_SA_DQS_DP<8>")
		)
		(pad "DF63" smd circle
			(at 14.635988 12.977114 270)
			(size 0.4318 0.4318)
			(layers "F.Cu" "F.Mask" "F.Paste")
			(net "M_H_CPU0_SA_DQ<26>")
		)
		(pad "DF65" smd circle
			(at 16.263874 12.977114 270)
			(size 0.4318 0.4318)
			(layers "F.Cu" "F.Mask" "F.Paste")
			(net "M_H_CPU0_SA_DQ<23>")
		)
		(pad "DF67" smd circle
			(at 17.89176 12.977114 270)
			(size 0.4318 0.4318)
			(layers "F.Cu" "F.Mask" "F.Paste")
			(net "M_H_CPU0_SA_DQS_DP<7>")
		)
		(pad "DF69" smd circle
			(at 19.519392 12.977114 270)
			(size 0.4318 0.4318)
			(layers "F.Cu" "F.Mask" "F.Paste")
			(net "M_H_CPU0_SA_DQ<18>")
		)
		(pad "DF71" smd circle
			(at 21.147278 12.977114 270)
			(size 0.4318 0.4318)
			(layers "F.Cu" "F.Mask" "F.Paste")
			(net "M_H_CPU0_SA_DQ<15>")
		)
		(pad "DF73" smd circle
			(at 22.77491 12.977114 270)
			(size 0.4318 0.4318)
			(layers "F.Cu" "F.Mask" "F.Paste")
			(net "M_H_CPU0_SA_DQS_DP<6>")
		)
		(pad "DF75" smd circle
			(at 24.402796 12.977114 270)
			(size 0.4318 0.4318)
			(layers "F.Cu" "F.Mask" "F.Paste")
			(net "M_H_CPU0_SA_DQ<10>")
		)
		(pad "DF77" smd circle
			(at 26.030682 12.977114 270)
			(size 0.4318 0.4318)
			(layers "F.Cu" "F.Mask" "F.Paste")
			(net "GND")
		)
		(pad "DF79" smd circle
			(at 27.658314 12.977114 270)
			(size 0.4318 0.4318)
			(layers "F.Cu" "F.Mask" "F.Paste")
			(net "GND")
		)
		(pad "DF81" smd circle
			(at 29.2862 12.977114 270)
			(size 0.4318 0.4318)
			(layers "F.Cu" "F.Mask" "F.Paste")
			(net "GND")
		)
		(pad "DF83" smd circle
			(at 30.914086 12.977114 270)
			(size 0.4318 0.4318)
			(layers "F.Cu" "F.Mask" "F.Paste")
			(net "GND")
		)
		(pad "DF85" smd circle
			(at 32.541718 12.977114 270)
			(size 0.4318 0.4318)
			(layers "F.Cu" "F.Mask" "F.Paste")
			(net "P5E_CPU0_PE3_TX_DN<9>")
		)
		(pad "DF87" smd circle
			(at 34.169604 12.977114 270)
			(size 0.4318 0.4318)
			(layers "F.Cu" "F.Mask" "F.Paste")
			(net "GND")
		)
		(pad "DF89" smd circle
			(at 35.797236 12.977114 270)
			(size 0.4318 0.4318)
			(layers "F.Cu" "F.Mask" "F.Paste")
			(net "P5E_CPU0_PE3_RX_DP<10>")
		)
		(pad "DF91" smd oval
			(at 37.425122 12.977114)
			(size 0.381 0.4826)
			(drill
				(offset 0 -0.0508)
			)
			(layers "F.Cu" "F.Mask" "F.Paste")
			(net "GND")
		)
		(pad "DG1" smd oval
			(at -37.425122 13.337286 180)
			(size 0.381 0.4826)
			(drill
				(offset 0 -0.0508)
			)
			(layers "F.Cu" "F.Mask" "F.Paste")
			(net "GND")
		)
		(pad "DG3" smd circle
			(at -35.797236 13.337286 270)
			(size 0.4318 0.4318)
			(layers "F.Cu" "F.Mask" "F.Paste")
			(net "UPI_CPU1_CPU0_P0P1_DN<10>")
		)
		(pad "DG5" smd circle
			(at -34.169604 13.337286 270)
			(size 0.4318 0.4318)
			(layers "F.Cu" "F.Mask" "F.Paste")
			(net "GND")
		)
		(pad "DG7" smd circle
			(at -32.541718 13.337286 270)
			(size 0.4318 0.4318)
			(layers "F.Cu" "F.Mask" "F.Paste")
			(net "UPI_CPU0_CPU1_P1P0_DP<9>")
		)
		(pad "DG9" smd circle
			(at -30.914086 13.337286 270)
			(size 0.4318 0.4318)
			(layers "F.Cu" "F.Mask" "F.Paste")
			(net "GND")
		)
		(pad "DG11" smd circle
			(at -29.2862 13.337286 270)
			(size 0.4318 0.4318)
			(layers "F.Cu" "F.Mask" "F.Paste")
			(net "P5E_CPU0_PE2_RX_DP<5>")
		)
		(pad "DG13" smd circle
			(at -27.658314 13.337286 270)
			(size 0.4318 0.4318)
			(layers "F.Cu" "F.Mask" "F.Paste")
			(net "GND")
		)
		(pad "DG15" smd circle
			(at -26.030682 13.337286 270)
			(size 0.4318 0.4318)
			(layers "F.Cu" "F.Mask" "F.Paste")
			(net "P5E_CPU0_PE2_TX_DP<5>")
		)
		(pad "DG17" smd circle
			(at -24.402796 13.337286 270)
			(size 0.4318 0.4318)
			(layers "F.Cu" "F.Mask" "F.Paste")
			(net "M_H_CPU0_SB_DQ<28>")
		)
		(pad "DG19" smd circle
			(at -22.77491 13.337286 270)
			(size 0.4318 0.4318)
			(layers "F.Cu" "F.Mask" "F.Paste")
			(net "M_H_CPU0_SB_DQ<27>")
		)
		(pad "DG21" smd circle
			(at -21.147278 13.337286 270)
			(size 0.4318 0.4318)
			(layers "F.Cu" "F.Mask" "F.Paste")
			(net "GND")
		)
		(pad "DG23" smd circle
			(at -19.519392 13.337286 270)
			(size 0.4318 0.4318)
			(layers "F.Cu" "F.Mask" "F.Paste")
			(net "M_H_CPU0_SB_DQ<14>")
		)
		(pad "DG25" smd circle
			(at -17.89176 13.337286 270)
			(size 0.4318 0.4318)
			(layers "F.Cu" "F.Mask" "F.Paste")
			(net "M_H_CPU0_SB_DQ<11>")
		)
		(pad "DG27" smd circle
			(at -16.263874 13.337286 270)
			(size 0.4318 0.4318)
			(layers "F.Cu" "F.Mask" "F.Paste")
			(net "GND")
		)
		(pad "DG29" smd circle
			(at -14.635988 13.337286 270)
			(size 0.4318 0.4318)
			(layers "F.Cu" "F.Mask" "F.Paste")
			(net "M_H_CPU0_SB_DQ<6>")
		)
		(pad "DG31" smd circle
			(at -13.008356 13.337286 270)
			(size 0.4318 0.4318)
			(layers "F.Cu" "F.Mask" "F.Paste")
			(net "M_H_CPU0_SB_DQ<3>")
		)
		(pad "DG33" smd circle
			(at -11.380724 13.337286 270)
			(size 0.4318 0.4318)
			(layers "F.Cu" "F.Mask" "F.Paste")
			(net "GND")
		)
		(pad "DG35" smd circle
			(at -9.752838 13.337286 270)
			(size 0.4318 0.4318)
			(layers "F.Cu" "F.Mask" "F.Paste")
			(net "M_H_CPU0_SB_CB<2>")
		)
		(pad "DG37" smd circle
			(at -8.124952 13.337286 270)
			(size 0.4318 0.4318)
			(layers "F.Cu" "F.Mask" "F.Paste")
			(net "M_H_CPU0_SB_CB<5>")
		)
		(pad "DG39" smd circle
			(at -6.49732 13.337286 270)
			(size 0.4318 0.4318)
			(layers "F.Cu" "F.Mask" "F.Paste")
			(net "GND")
		)
		(pad "DG41" smd circle
			(at -4.869434 13.337286 270)
			(size 0.4318 0.4318)
			(layers "F.Cu" "F.Mask" "F.Paste")
			(net "M_H_CPU0_SB_CA<1>")
		)
		(pad "DG43" smd circle
			(at -3.241802 13.337286 270)
			(size 0.4318 0.4318)
			(layers "F.Cu" "F.Mask" "F.Paste")
			(net "M_E_CPU0_SB_RSP<1>")
		)
		(pad "DG45" smd circle
			(at -1.613916 13.337286 270)
			(size 0.4318 0.4318)
			(layers "F.Cu" "F.Mask" "F.Paste")
			(net "GND")
		)
		(pad "DG48" smd circle
			(at 2.427732 13.447268 270)
			(size 0.4318 0.4318)
			(layers "F.Cu" "F.Mask" "F.Paste")
			(net "M_H_CPU0_SA_CA<3>")
		)
		(pad "DG50" smd circle
			(at 4.055618 13.447268 270)
			(size 0.4318 0.4318)
			(layers "F.Cu" "F.Mask" "F.Paste")
			(net "M_H_CPU0_SA_CS_N<1>")
		)
		(pad "DG52" smd circle
			(at 5.68325 13.447268 270)
			(size 0.4318 0.4318)
			(layers "F.Cu" "F.Mask" "F.Paste")
			(net "GND")
		)
		(pad "DG54" smd circle
			(at 7.311136 13.447268 270)
			(size 0.4318 0.4318)
			(layers "F.Cu" "F.Mask" "F.Paste")
			(net "M_H_CPU0_SA_CB<6>")
		)
		(pad "DG56" smd circle
			(at 8.939022 13.447268 270)
			(size 0.4318 0.4318)
			(layers "F.Cu" "F.Mask" "F.Paste")
			(net "M_H_CPU0_SA_CB<3>")
		)
		(pad "DG58" smd circle
			(at 10.566654 13.447268 270)
			(size 0.4318 0.4318)
			(layers "F.Cu" "F.Mask" "F.Paste")
			(net "GND")
		)
		(pad "DG60" smd circle
			(at 12.19454 13.447268 270)
			(size 0.4318 0.4318)
			(layers "F.Cu" "F.Mask" "F.Paste")
			(net "M_H_CPU0_SA_DQ<30>")
		)
		(pad "DG62" smd circle
			(at 13.822426 13.447268 270)
			(size 0.4318 0.4318)
			(layers "F.Cu" "F.Mask" "F.Paste")
			(net "M_H_CPU0_SA_DQ<27>")
		)
		(pad "DG64" smd circle
			(at 15.450058 13.447268 270)
			(size 0.4318 0.4318)
			(layers "F.Cu" "F.Mask" "F.Paste")
			(net "GND")
		)
		(pad "DG66" smd circle
			(at 17.07769 13.447268 270)
			(size 0.4318 0.4318)
			(layers "F.Cu" "F.Mask" "F.Paste")
			(net "M_H_CPU0_SA_DQ<22>")
		)
		(pad "DG68" smd circle
			(at 18.705576 13.447268 270)
			(size 0.4318 0.4318)
			(layers "F.Cu" "F.Mask" "F.Paste")
			(net "M_H_CPU0_SA_DQ<19>")
		)
	)
)
